# T6G (Grand Teton) — schematic netlist excerpt (pin names and nets, part order shuffled) for the footprints in the layout excerpt that follows; sources: Cadence DE-HDL packaged netlist, KiCad conversion of 04192023_DAF0TMB3IC0_F0TG_MB_C_brd_V02_OCP.brd

C1089  Q_CAP  0.1UF 25V 10% X7R  pkg 0402  page 258 : A = PVDD_33_S5_ADC_TIC ; B = GND
C1013  Q_CAP  1UF 4V 20% X6S  pkg 0201  page 312 : A = P0V9_CPU0_RT3_2A ; B = GND

Q148  MOSFET_NCH_DUAL  PJT138K IC  pkg SOT363XD  page 124
  S1  = GND
  G1  = HGX_DETECT_N
  D2  = HGX_DETECT_N_ISO
  S2  = GND
  G2  = HGX_DETECT
  D1  = HGX_DETECT

(kicad_pcb
	(version 20260206)
	(generator "pcbnew")
	(generator_version "10.0")
	(general
		(thickness 1.6)
		(legacy_teardrops no)
	)
	(paper "A4")
	(title_block
		(title "04192023_DAF0TMB3IC0_F0TG_MB_C_brd_V02_OCP.brd")
		(comment 1 "Grand Teton / footprints 6144-6146 of 8354")
	)
	(layers
		(0 "F.Cu" signal "TOP")
		(4 "In1.Cu" signal "GND")
		(6 "In2.Cu" signal "IN1")
		(8 "In3.Cu" signal "GND1")
		(10 "In4.Cu" signal "IN2")
		(12 "In5.Cu" signal "GND2")
		(14 "In6.Cu" signal "IN3")
		(16 "In7.Cu" signal "GND3")
		(18 "In8.Cu" signal "VCC")
		(20 "In9.Cu" signal "VCC1")
		(22 "In10.Cu" signal "GND4")
		(24 "In11.Cu" signal "IN4")
		(26 "In12.Cu" signal "GND5")
		(28 "In13.Cu" signal "IN5")
		(30 "In14.Cu" signal "GND6")
		(32 "In15.Cu" signal "IN6")
		(34 "In16.Cu" signal "GND7")
		(2 "B.Cu" signal "BOTTOM")
		(9 "F.Adhes" user "F.Adhesive")
		(11 "B.Adhes" user "B.Adhesive")
		(13 "F.Paste" user "Package Geometry/Pastemask Top")
		(15 "B.Paste" user "Package Geometry/Pastemask Bottom")
		(5 "F.SilkS" user "Ref Des/Silkscreen Top")
		(7 "B.SilkS" user "Ref Des/Silkscreen Bottom")
		(1 "F.Mask" user "Board Geometry/Soldermask Top")
		(3 "B.Mask" user "Board Geometry/Soldermask Bottom")
		(17 "Dwgs.User" user "User.Drawings")
		(19 "Cmts.User" user "User.Comments")
		(21 "Eco1.User" user "User.Eco1")
		(23 "Eco2.User" user "User.Eco2")
		(25 "Edge.Cuts" user "Board Geometry/Outline")
		(27 "Margin" user)
		(31 "F.CrtYd" user "Package Geometry/Place Bound Top")
		(29 "B.CrtYd" user "Package Geometry/Place Bound Bottom")
		(35 "F.Fab" user "Ref Des/Assembly Top")
		(33 "B.Fab" user "Ref Des/Assembly Bottom")
	)
	(footprint ""
		(layer "B.Cu")
		(at 228.479604 -327.56602 180)
		(property "Reference" "C1089"
			(at 0 0 0)
			(layer "B.SilkS")
			(hide yes)
			(effects
				(font
					(size 1.27 1.27)
				)
				(justify mirror)
			)
		)
		(property "Value" ""
			(at 0 0 0)
			(layer "B.Fab")
			(effects
				(font
					(size 1.27 1.27)
				)
				(justify mirror)
			)
		)
		(duplicate_pad_numbers_are_jumpers no)
		(fp_line
			(start 0.7874 0.4064)
			(end 0.7874 -0.4064)
			(stroke
				(width 0.1524)
				(type default)
			)
			(layer "B.SilkS")
		)
		(fp_line
			(start 0.7874 -0.4064)
			(end -0.7874 -0.4064)
			(stroke
				(width 0.1524)
				(type default)
			)
			(layer "B.SilkS")
		)
		(fp_line
			(start -0.7874 0.4064)
			(end 0.7874 0.4064)
			(stroke
				(width 0.1524)
				(type default)
			)
			(layer "B.SilkS")
		)
		(fp_line
			(start -0.7874 -0.4064)
			(end -0.7874 0.4064)
			(stroke
				(width 0.1524)
				(type default)
			)
			(layer "B.SilkS")
		)
		(fp_line
			(start 0.67945 0.3048)
			(end 0.67945 -0.305054)
			(stroke
				(width 0.1)
				(type default)
			)
			(layer "B.Fab")
		)
		(fp_line
			(start 0.67945 -0.305054)
			(end 0.12065 -0.305054)
			(stroke
				(width 0.1)
				(type default)
			)
			(layer "B.Fab")
		)
		(fp_line
			(start 0.12065 0.3048)
			(end 0.67945 0.3048)
			(stroke
				(width 0.1)
				(type default)
			)
			(layer "B.Fab")
		)
		(fp_line
			(start 0.12065 0.2794)
			(end 0.12065 0.3048)
			(stroke
				(width 0.1)
				(type default)
			)
			(layer "B.Fab")
		)
		(fp_line
			(start 0.12065 -0.2794)
			(end -0.12065 -0.2794)
			(stroke
				(width 0.1)
				(type default)
			)
			(layer "B.Fab")
		)
		(fp_line
			(start 0.12065 -0.305054)
			(end 0.12065 -0.2794)
			(stroke
				(width 0.1)
				(type default)
			)
			(layer "B.Fab")
		)
		(fp_line
			(start -0.120396 0.3048)
			(end -0.120396 0.2794)
			(stroke
				(width 0.1)
				(type default)
			)
			(layer "B.Fab")
		)
		(fp_line
			(start -0.120396 0.2794)
			(end 0.12065 0.2794)
			(stroke
				(width 0.1)
				(type default)
			)
			(layer "B.Fab")
		)
		(fp_line
			(start -0.12065 -0.2794)
			(end -0.12065 -0.3048)
			(stroke
				(width 0.1)
				(type default)
			)
			(layer "B.Fab")
		)
		(fp_line
			(start -0.12065 -0.3048)
			(end -0.67945 -0.3048)
			(stroke
				(width 0.1)
				(type default)
			)
			(layer "B.Fab")
		)
		(fp_line
			(start -0.67945 0.3048)
			(end -0.120396 0.3048)
			(stroke
				(width 0.1)
				(type default)
			)
			(layer "B.Fab")
		)
		(fp_line
			(start -0.67945 -0.3048)
			(end -0.67945 0.3048)
			(stroke
				(width 0.1)
				(type default)
			)
			(layer "B.Fab")
		)
		(pad "1" smd circle
			(at 0.40005 0)
			(size 0 0)
			(layers "B.Cu" "B.Mask" "B.Paste")
			(net "PVDD_33_S5_ADC_TIC")
		)
		(pad "2" smd circle
			(at -0.40005 0)
			(size 0 0)
			(layers "B.Cu" "B.Mask" "B.Paste")
			(net "GND")
		)
	)
	(footprint ""
		(layer "B.Cu")
		(at 109.22 -415.036 -90)
		(property "Reference" "Q148"
			(at 4.3942 0.12827 270)
			(unlocked yes)
			(layer "B.SilkS")
			(effects
				(font
					(size 0.7874 0.5842)
					(thickness 0.1524)
				)
				(justify left mirror)
			)
		)
		(property "Value" ""
			(at 0 0 90)
			(layer "B.Fab")
			(effects
				(font
					(size 1.27 1.27)
				)
				(justify mirror)
			)
		)
		(duplicate_pad_numbers_are_jumpers no)
		(fp_line
			(start -1.332738 1.100074)
			(end 1.332738 1.100074)
			(stroke
				(width 0.1524)
				(type default)
			)
			(layer "B.SilkS")
		)
		(fp_line
			(start 1.332738 1.100074)
			(end 1.332738 -1.100074)
			(stroke
				(width 0.1524)
				(type default)
			)
			(layer "B.SilkS")
		)
		(fp_line
			(start 0 -0.541274)
			(end -0.4826 -1.100074)
			(stroke
				(width 0.1524)
				(type default)
			)
			(layer "B.SilkS")
		)
		(fp_line
			(start -1.332738 -1.100074)
			(end -1.332738 1.100074)
			(stroke
				(width 0.1524)
				(type default)
			)
			(layer "B.SilkS")
		)
		(fp_line
			(start -0.4826 -1.100074)
			(end -1.332738 -1.100074)
			(stroke
				(width 0.1524)
				(type default)
			)
			(layer "B.SilkS")
		)
		(fp_line
			(start 0.4826 -1.100074)
			(end 0 -0.541274)
			(stroke
				(width 0.1524)
				(type default)
			)
			(layer "B.SilkS")
		)
		(fp_line
			(start 1.332738 -1.100074)
			(end 0.4826 -1.100074)
			(stroke
				(width 0.1524)
				(type default)
			)
			(layer "B.SilkS")
		)
		(fp_poly
			(pts
				(xy 0.513334 -1.311148) (xy 0.295402 -2.065274) (xy -0.220726 -1.589278)
			)
			(stroke
				(width 0)
				(type default)
			)
			(fill yes)
			(layer "B.SilkS")
		)
		(fp_line
			(start -0.674878 1.100074)
			(end 0.674878 1.100074)
			(stroke
				(width 0.1)
				(type default)
			)
			(layer "B.Fab")
		)
		(fp_line
			(start 0.674878 1.100074)
			(end 0.674878 -1.100074)
			(stroke
				(width 0.1)
				(type default)
			)
			(layer "B.Fab")
		)
		(fp_line
			(start -0.674878 -1.100074)
			(end -0.674878 1.100074)
			(stroke
				(width 0.1)
				(type default)
			)
			(layer "B.Fab")
		)
		(fp_line
			(start 0.674878 -1.100074)
			(end -0.674878 -1.100074)
			(stroke
				(width 0.1)
				(type default)
			)
			(layer "B.Fab")
		)
		(fp_poly
			(pts
				(xy 2.2352 -0.298958) (xy 2.2352 -1.001014) (xy 1.533144 -0.649986)
			)
			(stroke
				(width 0)
				(type default)
			)
			(fill yes)
			(layer "B.Fab")
		)
		(pad "1" smd rect
			(at 0.94996 -0.649986)
			(size 0.4318 0.508)
			(layers "B.Cu" "B.Mask" "B.Paste")
			(net "GND")
		)
		(pad "2" smd rect
			(at 0.94996 0)
			(size 0.4318 0.508)
			(layers "B.Cu" "B.Mask" "B.Paste")
			(net "HGX_DETECT_N")
		)
		(pad "3" smd rect
			(at 0.94996 0.649986)
			(size 0.4318 0.508)
			(layers "B.Cu" "B.Mask" "B.Paste")
			(net "HGX_DETECT_N_ISO")
		)
		(pad "4" smd rect
			(at -0.94996 0.649986)
			(size 0.4318 0.508)
			(layers "B.Cu" "B.Mask" "B.Paste")
			(net "GND")
		)
		(pad "5" smd rect
			(at -0.94996 0)
			(size 0.4318 0.508)
			(layers "B.Cu" "B.Mask" "B.Paste")
			(net "HGX_DETECT")
		)
		(pad "6" smd rect
			(at -0.94996 -0.649986)
			(size 0.4318 0.508)
			(layers "B.Cu" "B.Mask" "B.Paste")
			(net "HGX_DETECT")
		)
	)
	(footprint ""
		(layer "B.Cu")
		(at 372.878604 -395.148562 90)
		(property "Reference" "C1013"
			(at 0 0 90)
			(layer "B.SilkS")
			(hide yes)
			(effects
				(font
					(size 1.27 1.27)
				)
				(justify mirror)
			)
		)
		(property "Value" ""
			(at 0 0 90)
			(layer "B.Fab")
			(effects
				(font
					(size 1.27 1.27)
				)
				(justify mirror)
			)
		)
		(duplicate_pad_numbers_are_jumpers no)
		(fp_line
			(start 0.299974 -0.150114)
			(end -0.299974 -0.150114)
			(stroke
				(width 0.1)
				(type default)
			)
			(layer "B.Fab")
		)
		(fp_line
			(start -0.299974 -0.150114)
			(end -0.299974 0.150114)
			(stroke
				(width 0.1)
				(type default)
			)
			(layer "B.Fab")
		)
		(fp_line
			(start 0.299974 0.150114)
			(end 0.299974 -0.150114)
			(stroke
				(width 0.1)
				(type default)
			)
			(layer "B.Fab")
		)
		(fp_line
			(start -0.299974 0.150114)
			(end 0.299974 0.150114)
			(stroke
				(width 0.1)
				(type default)
			)
			(layer "B.Fab")
		)
		(pad "1" smd rect
			(at 0.2667 0 270)
			(size 0.3048 0.381)
			(layers "B.Cu" "B.Mask" "B.Paste")
			(net "P0V9_CPU0_RT3_2A")
		)
		(pad "2" smd rect
			(at -0.2667 0 270)
			(size 0.3048 0.381)
			(layers "B.Cu" "B.Mask" "B.Paste")
			(net "GND")
		)
	)
)
